# T6G (Grand Teton) — schematic netlist excerpt (pin names and nets, part order shuffled) for the footprints in the layout excerpt that follows; sources: Cadence DE-HDL packaged netlist, KiCad conversion of 04192023_DAF0TMB3IC0_F0TG_MB_C_brd_V02_OCP.brd

PC1869  Q_CAP  0.1UF 25V 10% X7R  pkg 0402  page 190 : A = P3V3_AUX ; B = GND
R156  Q_RES  0 5% CHIP  pkg 0402LF  page 27 : A = CPU0_XTRIG_R2_L4 ; B = CPU0_XTRIG_L4
PC353_3  Q_CAP  22UF 16V 20% X6S  pkg C0805  page 216 : A = SW_P12V_AUX_PVDDCR_SOC_P1_FLT ; B = GND

(kicad_pcb
	(version 20260206)
	(generator "pcbnew")
	(generator_version "10.0")
	(general
		(thickness 1.6)
		(legacy_teardrops no)
	)
	(paper "A4")
	(title_block
		(title "04192023_DAF0TMB3IC0_F0TG_MB_C_brd_V02_OCP.brd")
		(comment 1 "Grand Teton / footprints 7599-7601 of 8354")
	)
	(layers
		(0 "F.Cu" signal "TOP")
		(4 "In1.Cu" signal "GND")
		(6 "In2.Cu" signal "IN1")
		(8 "In3.Cu" signal "GND1")
		(10 "In4.Cu" signal "IN2")
		(12 "In5.Cu" signal "GND2")
		(14 "In6.Cu" signal "IN3")
		(16 "In7.Cu" signal "GND3")
		(18 "In8.Cu" signal "VCC")
		(20 "In9.Cu" signal "VCC1")
		(22 "In10.Cu" signal "GND4")
		(24 "In11.Cu" signal "IN4")
		(26 "In12.Cu" signal "GND5")
		(28 "In13.Cu" signal "IN5")
		(30 "In14.Cu" signal "GND6")
		(32 "In15.Cu" signal "IN6")
		(34 "In16.Cu" signal "GND7")
		(2 "B.Cu" signal "BOTTOM")
		(9 "F.Adhes" user "F.Adhesive")
		(11 "B.Adhes" user "B.Adhesive")
		(13 "F.Paste" user "Package Geometry/Pastemask Top")
		(15 "B.Paste" user "Package Geometry/Pastemask Bottom")
		(5 "F.SilkS" user "Ref Des/Silkscreen Top")
		(7 "B.SilkS" user "Ref Des/Silkscreen Bottom")
		(1 "F.Mask" user "Board Geometry/Soldermask Top")
		(3 "B.Mask" user "Board Geometry/Soldermask Bottom")
		(17 "Dwgs.User" user "User.Drawings")
		(19 "Cmts.User" user "User.Comments")
		(21 "Eco1.User" user "User.Eco1")
		(23 "Eco2.User" user "User.Eco2")
		(25 "Edge.Cuts" user "Board Geometry/Outline")
		(27 "Margin" user)
		(31 "F.CrtYd" user "Package Geometry/Place Bound Top")
		(29 "B.CrtYd" user "Package Geometry/Place Bound Bottom")
		(35 "F.Fab" user "Ref Des/Assembly Top")
		(33 "B.Fab" user "Ref Des/Assembly Bottom")
	)
	(footprint ""
		(layer "B.Cu")
		(at 459.053184 -65.794382 90)
		(property "Reference" "PC1869"
			(at 0 0 90)
			(layer "B.SilkS")
			(hide yes)
			(effects
				(font
					(size 1.27 1.27)
				)
				(justify mirror)
			)
		)
		(property "Value" ""
			(at 0 0 90)
			(layer "B.Fab")
			(effects
				(font
					(size 1.27 1.27)
				)
				(justify mirror)
			)
		)
		(duplicate_pad_numbers_are_jumpers no)
		(fp_line
			(start 0.7874 -0.4064)
			(end -0.7874 -0.4064)
			(stroke
				(width 0.1524)
				(type default)
			)
			(layer "B.SilkS")
		)
		(fp_line
			(start -0.7874 -0.4064)
			(end -0.7874 0.4064)
			(stroke
				(width 0.1524)
				(type default)
			)
			(layer "B.SilkS")
		)
		(fp_line
			(start 0.7874 0.4064)
			(end 0.7874 -0.4064)
			(stroke
				(width 0.1524)
				(type default)
			)
			(layer "B.SilkS")
		)
		(fp_line
			(start -0.7874 0.4064)
			(end 0.7874 0.4064)
			(stroke
				(width 0.1524)
				(type default)
			)
			(layer "B.SilkS")
		)
		(fp_line
			(start 0.67945 -0.305054)
			(end 0.12065 -0.305054)
			(stroke
				(width 0.1)
				(type default)
			)
			(layer "B.Fab")
		)
		(fp_line
			(start 0.12065 -0.305054)
			(end 0.12065 -0.2794)
			(stroke
				(width 0.1)
				(type default)
			)
			(layer "B.Fab")
		)
		(fp_line
			(start -0.12065 -0.3048)
			(end -0.67945 -0.3048)
			(stroke
				(width 0.1)
				(type default)
			)
			(layer "B.Fab")
		)
		(fp_line
			(start -0.67945 -0.3048)
			(end -0.67945 0.3048)
			(stroke
				(width 0.1)
				(type default)
			)
			(layer "B.Fab")
		)
		(fp_line
			(start 0.12065 -0.2794)
			(end -0.12065 -0.2794)
			(stroke
				(width 0.1)
				(type default)
			)
			(layer "B.Fab")
		)
		(fp_line
			(start -0.12065 -0.2794)
			(end -0.12065 -0.3048)
			(stroke
				(width 0.1)
				(type default)
			)
			(layer "B.Fab")
		)
		(fp_line
			(start 0.12065 0.2794)
			(end 0.12065 0.3048)
			(stroke
				(width 0.1)
				(type default)
			)
			(layer "B.Fab")
		)
		(fp_line
			(start -0.120396 0.2794)
			(end 0.12065 0.2794)
			(stroke
				(width 0.1)
				(type default)
			)
			(layer "B.Fab")
		)
		(fp_line
			(start 0.67945 0.3048)
			(end 0.67945 -0.305054)
			(stroke
				(width 0.1)
				(type default)
			)
			(layer "B.Fab")
		)
		(fp_line
			(start 0.12065 0.3048)
			(end 0.67945 0.3048)
			(stroke
				(width 0.1)
				(type default)
			)
			(layer "B.Fab")
		)
		(fp_line
			(start -0.120396 0.3048)
			(end -0.120396 0.2794)
			(stroke
				(width 0.1)
				(type default)
			)
			(layer "B.Fab")
		)
		(fp_line
			(start -0.67945 0.3048)
			(end -0.120396 0.3048)
			(stroke
				(width 0.1)
				(type default)
			)
			(layer "B.Fab")
		)
		(pad "1" smd circle
			(at 0.40005 0 270)
			(size 0 0)
			(layers "B.Cu" "B.Mask" "B.Paste")
			(net "P3V3_AUX")
		)
		(pad "2" smd circle
			(at -0.40005 0 270)
			(size 0 0)
			(layers "B.Cu" "B.Mask" "B.Paste")
			(net "GND")
		)
	)
	(footprint ""
		(layer "B.Cu")
		(at 127.536448 -156.393134 -90)
		(property "Reference" "PC353_3"
			(at 0 0 90)
			(layer "B.SilkS")
			(hide yes)
			(effects
				(font
					(size 1.27 1.27)
				)
				(justify mirror)
			)
		)
		(property "Value" ""
			(at 0 0 90)
			(layer "B.Fab")
			(effects
				(font
					(size 1.27 1.27)
				)
				(justify mirror)
			)
		)
		(duplicate_pad_numbers_are_jumpers no)
		(fp_line
			(start -1.524 0.762)
			(end 1.524 0.762)
			(stroke
				(width 0.1524)
				(type default)
			)
			(layer "B.SilkS")
		)
		(fp_line
			(start 1.524 0.762)
			(end 1.524 -0.762)
			(stroke
				(width 0.1524)
				(type default)
			)
			(layer "B.SilkS")
		)
		(fp_line
			(start -1.524 -0.762)
			(end -1.524 0.762)
			(stroke
				(width 0.1524)
				(type default)
			)
			(layer "B.SilkS")
		)
		(fp_line
			(start 1.524 -0.762)
			(end -1.524 -0.762)
			(stroke
				(width 0.1524)
				(type default)
			)
			(layer "B.SilkS")
		)
		(fp_line
			(start -1.1049 0.724916)
			(end -1.1049 -0.724916)
			(stroke
				(width 0.1)
				(type default)
			)
			(layer "B.Fab")
		)
		(fp_line
			(start 1.1049 0.724916)
			(end -1.1049 0.724916)
			(stroke
				(width 0.1)
				(type default)
			)
			(layer "B.Fab")
		)
		(fp_line
			(start -1.1049 -0.724916)
			(end 1.1049 -0.724916)
			(stroke
				(width 0.1)
				(type default)
			)
			(layer "B.Fab")
		)
		(fp_line
			(start 1.1049 -0.724916)
			(end 1.1049 0.724916)
			(stroke
				(width 0.1)
				(type default)
			)
			(layer "B.Fab")
		)
		(pad "1" smd rect
			(at 0.889 0 270)
			(size 1.016 1.27)
			(layers "B.Cu" "B.Mask" "B.Paste")
			(net "SW_P12V_AUX_PVDDCR_SOC_P1_FLT")
		)
		(pad "2" smd rect
			(at -0.889 0 270)
			(size 1.016 1.27)
			(layers "B.Cu" "B.Mask" "B.Paste")
			(net "GND")
		)
	)
	(footprint ""
		(layer "B.Cu")
		(at 325.799958 -203.917296 90)
		(property "Reference" "R156"
			(at 0 0 90)
			(layer "B.SilkS")
			(hide yes)
			(effects
				(font
					(size 1.27 1.27)
				)
				(justify mirror)
			)
		)
		(property "Value" ""
			(at 0 0 90)
			(layer "B.Fab")
			(effects
				(font
					(size 1.27 1.27)
				)
				(justify mirror)
			)
		)
		(duplicate_pad_numbers_are_jumpers no)
		(fp_line
			(start 0.7874 -0.4064)
			(end -0.7874 -0.4064)
			(stroke
				(width 0.1524)
				(type default)
			)
			(layer "B.SilkS")
		)
		(fp_line
			(start -0.7874 -0.4064)
			(end -0.7874 0.4064)
			(stroke
				(width 0.1524)
				(type default)
			)
			(layer "B.SilkS")
		)
		(fp_line
			(start 0.7874 0.4064)
			(end 0.7874 -0.4064)
			(stroke
				(width 0.1524)
				(type default)
			)
			(layer "B.SilkS")
		)
		(fp_line
			(start -0.7874 0.4064)
			(end 0.7874 0.4064)
			(stroke
				(width 0.1524)
				(type default)
			)
			(layer "B.SilkS")
		)
		(fp_line
			(start 0.67945 -0.305054)
			(end 0.12065 -0.305054)
			(stroke
				(width 0.1)
				(type default)
			)
			(layer "B.Fab")
		)
		(fp_line
			(start 0.12065 -0.305054)
			(end 0.12065 -0.2794)
			(stroke
				(width 0.1)
				(type default)
			)
			(layer "B.Fab")
		)
		(fp_line
			(start -0.12065 -0.3048)
			(end -0.67945 -0.3048)
			(stroke
				(width 0.1)
				(type default)
			)
			(layer "B.Fab")
		)
		(fp_line
			(start -0.67945 -0.3048)
			(end -0.67945 0.3048)
			(stroke
				(width 0.1)
				(type default)
			)
			(layer "B.Fab")
		)
		(fp_line
			(start 0.12065 -0.2794)
			(end -0.12065 -0.2794)
			(stroke
				(width 0.1)
				(type default)
			)
			(layer "B.Fab")
		)
		(fp_line
			(start -0.12065 -0.2794)
			(end -0.12065 -0.3048)
			(stroke
				(width 0.1)
				(type default)
			)
			(layer "B.Fab")
		)
		(fp_line
			(start 0.12065 0.2794)
			(end 0.12065 0.3048)
			(stroke
				(width 0.1)
				(type default)
			)
			(layer "B.Fab")
		)
		(fp_line
			(start -0.120396 0.2794)
			(end 0.12065 0.2794)
			(stroke
				(width 0.1)
				(type default)
			)
			(layer "B.Fab")
		)
		(fp_line
			(start 0.67945 0.3048)
			(end 0.67945 -0.305054)
			(stroke
				(width 0.1)
				(type default)
			)
			(layer "B.Fab")
		)
		(fp_line
			(start 0.12065 0.3048)
			(end 0.67945 0.3048)
			(stroke
				(width 0.1)
				(type default)
			)
			(layer "B.Fab")
		)
		(fp_line
			(start -0.120396 0.3048)
			(end -0.120396 0.2794)
			(stroke
				(width 0.1)
				(type default)
			)
			(layer "B.Fab")
		)
		(fp_line
			(start -0.67945 0.3048)
			(end -0.120396 0.3048)
			(stroke
				(width 0.1)
				(type default)
			)
			(layer "B.Fab")
		)
		(pad "1" smd circle
			(at 0.40005 0 270)
			(size 0 0)
			(layers "B.Cu" "B.Mask" "B.Paste")
			(net "CPU0_XTRIG_R2_L4")
		)
		(pad "2" smd circle
			(at -0.40005 0 270)
			(size 0 0)
			(layers "B.Cu" "B.Mask" "B.Paste")
			(net "CPU0_XTRIG_L4")
		)
	)
)
